(kicad_pcb
	(version 20260206)
	(generator "pcbnew")
	(generator_version "10.0")
	(general
		(thickness 1.6)
		(legacy_teardrops no)
	)
	(paper "A4")
	(title_block
		(title "Wiwynn_Tioga_Pass_MB.brd")
		(comment 1 "Tioga Pass / footprints 2289-2294 of 4770")
	)
	(layers
		(0 "F.Cu" signal "TOP")
		(4 "In1.Cu" signal "L2GND")
		(6 "In2.Cu" signal "L3")
		(8 "In3.Cu" signal "L4GND")
		(10 "In4.Cu" signal "L5")
		(12 "In5.Cu" signal "L6GND")
		(14 "In6.Cu" signal "L7VCC")
		(16 "In7.Cu" signal "L8VCC")
		(18 "In8.Cu" signal "L9GND")
		(20 "In9.Cu" signal "L10")
		(22 "In10.Cu" signal "L11GND")
		(24 "In11.Cu" signal "L12")
		(26 "In12.Cu" signal "L13GND")
		(2 "B.Cu" signal "BOTTOM")
		(9 "F.Adhes" user "F.Adhesive")
		(11 "B.Adhes" user "B.Adhesive")
		(13 "F.Paste" user "Package Geometry/Pastemask Top")
		(15 "B.Paste" user "Package Geometry/Pastemask Bottom")
		(5 "F.SilkS" user "Ref Des/Silkscreen Top")
		(7 "B.SilkS" user "Ref Des/Silkscreen Bottom")
		(1 "F.Mask" user "Board Geometry/Soldermask Top")
		(3 "B.Mask" user "Board Geometry/Soldermask Bottom")
		(17 "Dwgs.User" user "User.Drawings")
		(19 "Cmts.User" user "User.Comments")
		(21 "Eco1.User" user "User.Eco1")
		(23 "Eco2.User" user "User.Eco2")
		(25 "Edge.Cuts" user "Board Geometry/Outline")
		(27 "Margin" user)
		(31 "F.CrtYd" user "Package Geometry/Place Bound Top")
		(29 "B.CrtYd" user "Package Geometry/Place Bound Bottom")
		(35 "F.Fab" user "Ref Des/Assembly Top")
		(33 "B.Fab" user "Ref Des/Assembly Bottom")
	)
	(footprint ""
		(layer "F.Cu")
		(at 380.746 -88.2015)
		(property "Reference" "R25W68"
			(at -0.8382 -0.67818 0)
			(unlocked yes)
			(layer "F.SilkS")
			(effects
				(font
					(size 0.4064 0.254)
					(thickness 0.1524)
				)
				(justify left)
			)
		)
		(property "Value" ""
			(at 0 0 0)
			(layer "F.Fab")
			(effects
				(font
					(size 1.27 1.27)
				)
			)
		)
		(duplicate_pad_numbers_are_jumpers no)
		(fp_poly
			(pts
				(xy -0.2794 -0.1016) (xy 0.2794 -0.1016) (xy 0.2794 0.9906) (xy -0.2794 0.9906)
			)
			(stroke
				(width 0)
				(type default)
			)
			(fill no)
			(layer "F.CrtYd")
		)
		(fp_line
			(start -0.2794 -0.1016)
			(end -0.2794 0.9906)
			(stroke
				(width 0.1)
				(type default)
			)
			(layer "F.Fab")
		)
		(fp_line
			(start -0.2794 0.9906)
			(end 0.2794 0.9906)
			(stroke
				(width 0.1)
				(type default)
			)
			(layer "F.Fab")
		)
		(fp_line
			(start 0.2794 -0.1016)
			(end -0.2794 -0.1016)
			(stroke
				(width 0.1)
				(type default)
			)
			(layer "F.Fab")
		)
		(fp_line
			(start 0.2794 0.9906)
			(end 0.2794 -0.1016)
			(stroke
				(width 0.1)
				(type default)
			)
			(layer "F.Fab")
		)
		(pad "1" smd rect
			(at 0 0)
			(size 0.508 0.508)
			(layers "F.Cu" "F.Mask" "F.Paste")
			(net "LPC_LAD3_IO3")
		)
		(pad "2" smd rect
			(at 0 0.889)
			(size 0.508 0.508)
			(layers "F.Cu" "F.Mask" "F.Paste")
			(net "LPC_LAD3_IO3_R")
		)
		(zone
			(layer "F.Cu")
			(hatch none 0.5)
			(connect_pads
				(clearance 0)
			)
			(min_thickness 0.25)
			(keepout
				(tracks allowed)
				(vias not_allowed)
				(pads allowed)
				(copperpour not_allowed)
				(footprints allowed)
			)
			(placement
				(enabled no)
				(sheetname "")
			)
			(fill
				(thermal_gap 0.5)
				(thermal_bridge_width 0.5)
				(island_removal_mode 0)
			)
			(polygon
				(pts
					(xy 380.492 -87.9475) (xy 381 -87.9475) (xy 381 -87.5665) (xy 380.492 -87.5665)
				)
			)
		)
		(zone
			(layer "F.Cu")
			(hatch none 0.5)
			(connect_pads
				(clearance 0)
			)
			(min_thickness 0.25)
			(keepout
				(tracks not_allowed)
				(vias allowed)
				(pads allowed)
				(copperpour not_allowed)
				(footprints allowed)
			)
			(placement
				(enabled no)
				(sheetname "")
			)
			(fill
				(thermal_gap 0.5)
				(thermal_bridge_width 0.5)
				(island_removal_mode 0)
			)
			(polygon
				(pts
					(xy 380.492 -87.5665) (xy 381 -87.5665) (xy 381 -87.9475) (xy 380.492 -87.9475)
				)
			)
		)
	)
	(footprint ""
		(layer "F.Cu")
		(at 320.194432 -22.740112 90)
		(property "Reference" "C6F6"
			(at 0 0 90)
			(layer "F.SilkS")
			(hide yes)
			(effects
				(font
					(size 1.27 1.27)
				)
			)
		)
		(property "Value" ""
			(at 0 0 90)
			(layer "F.Fab")
			(effects
				(font
					(size 1.27 1.27)
				)
			)
		)
		(duplicate_pad_numbers_are_jumpers no)
		(fp_poly
			(pts
				(xy -0.4953 -0.2032) (xy 0.4953 -0.2032) (xy 0.4953 1.6002) (xy -0.4953 1.6002)
			)
			(stroke
				(width 0)
				(type default)
			)
			(fill no)
			(layer "F.CrtYd")
		)
		(fp_line
			(start 0.4953 -0.2032)
			(end 0.4953 1.6002)
			(stroke
				(width 0.1)
				(type default)
			)
			(layer "F.Fab")
		)
		(fp_line
			(start -0.4953 -0.2032)
			(end 0.4953 -0.2032)
			(stroke
				(width 0.1)
				(type default)
			)
			(layer "F.Fab")
		)
		(fp_line
			(start 0.4953 1.6002)
			(end -0.4953 1.6002)
			(stroke
				(width 0.1)
				(type default)
			)
			(layer "F.Fab")
		)
		(fp_line
			(start -0.4953 1.6002)
			(end -0.4953 -0.2032)
			(stroke
				(width 0.1)
				(type default)
			)
			(layer "F.Fab")
		)
		(pad "1" smd rect
			(at 0 0 90)
			(size 0.762 0.889)
			(layers "F.Cu" "F.Mask" "F.Paste")
			(net "PVPP_ABC")
		)
		(pad "2" smd rect
			(at 0 1.397 90)
			(size 0.762 0.889)
			(layers "F.Cu" "F.Mask" "F.Paste")
			(net "GND")
		)
		(zone
			(layer "F.Cu")
			(hatch none 0.5)
			(connect_pads
				(clearance 0)
			)
			(min_thickness 0.25)
			(keepout
				(tracks not_allowed)
				(vias allowed)
				(pads allowed)
				(copperpour not_allowed)
				(footprints allowed)
			)
			(placement
				(enabled no)
				(sheetname "")
			)
			(fill
				(thermal_gap 0.5)
				(thermal_bridge_width 0.5)
				(island_removal_mode 0)
			)
			(polygon
				(pts
					(xy 320.638932 -22.359112) (xy 320.638932 -23.121112) (xy 321.146932 -23.121112) (xy 321.146932 -22.359112)
				)
			)
		)
	)
	(footprint ""
		(layer "F.Cu")
		(at 111.000032 -3.3528 90)
		(property "Reference" "C3G6"
			(at 1.848866 0.752348 90)
			(unlocked yes)
			(layer "F.SilkS")
			(effects
				(font
					(size 1.27 0.9652)
					(thickness 0.1524)
				)
			)
		)
		(property "Value" ""
			(at 0 0 90)
			(layer "F.Fab")
			(effects
				(font
					(size 1.27 1.27)
				)
			)
		)
		(duplicate_pad_numbers_are_jumpers no)
		(fp_rect
			(start -0.500126 1.598422)
			(end 0.500126 -0.201422)
			(stroke
				(width 0)
				(type default)
			)
			(fill no)
			(layer "F.CrtYd")
		)
		(fp_line
			(start 0.500126 -0.201422)
			(end 0.500126 1.598422)
			(stroke
				(width 0.1)
				(type default)
			)
			(layer "F.Fab")
		)
		(fp_line
			(start -0.500126 -0.201422)
			(end 0.500126 -0.201422)
			(stroke
				(width 0.1)
				(type default)
			)
			(layer "F.Fab")
		)
		(fp_line
			(start 0.500126 1.598422)
			(end -0.500126 1.598422)
			(stroke
				(width 0.1)
				(type default)
			)
			(layer "F.Fab")
		)
		(fp_line
			(start -0.500126 1.598422)
			(end -0.500126 -0.201422)
			(stroke
				(width 0.1)
				(type default)
			)
			(layer "F.Fab")
		)
		(pad "1" smd rect
			(at 0 0)
			(size 0.889 0.9906)
			(layers "F.Cu" "F.Mask" "F.Paste")
			(net "PVDDQ_GHJ")
		)
		(pad "2" smd rect
			(at 0 1.397)
			(size 0.889 0.9906)
			(layers "F.Cu" "F.Mask" "F.Paste")
			(net "GND")
		)
		(zone
			(layer "F.Cu")
			(hatch none 0.5)
			(connect_pads
				(clearance 0)
			)
			(min_thickness 0.25)
			(keepout
				(tracks allowed)
				(vias not_allowed)
				(pads allowed)
				(copperpour not_allowed)
				(footprints allowed)
			)
			(placement
				(enabled no)
				(sheetname "")
			)
			(fill
				(thermal_gap 0.5)
				(thermal_bridge_width 0.5)
				(island_removal_mode 0)
			)
			(polygon
				(pts
					(xy 111.952532 -2.8575) (xy 111.952532 -3.8481) (xy 111.444532 -3.8481) (xy 111.444532 -2.8575)
				)
			)
		)
		(zone
			(layer "F.Cu")
			(hatch none 0.5)
			(connect_pads
				(clearance 0)
			)
			(min_thickness 0.25)
			(keepout
				(tracks not_allowed)
				(vias allowed)
				(pads allowed)
				(copperpour not_allowed)
				(footprints allowed)
			)
			(placement
				(enabled no)
				(sheetname "")
			)
			(fill
				(thermal_gap 0.5)
				(thermal_bridge_width 0.5)
				(island_removal_mode 0)
			)
			(polygon
				(pts
					(xy 111.952532 -2.8575) (xy 111.952532 -3.8481) (xy 111.444532 -3.8481) (xy 111.444532 -2.8575)
				)
			)
		)
	)
	(footprint ""
		(layer "F.Cu")
		(at 347.032072 -97.54489 -90)
		(property "Reference" "EU7C1"
			(at 4.64566 -1.565148 0)
			(unlocked yes)
			(layer "F.SilkS")
			(effects
				(font
					(size 0.7874 0.5842)
					(thickness 0.1524)
				)
			)
		)
		(property "Value" ""
			(at 0 0 270)
			(layer "F.Fab")
			(effects
				(font
					(size 1.27 1.27)
				)
			)
		)
		(duplicate_pad_numbers_are_jumpers no)
		(fp_line
			(start -3.0099 3.429)
			(end -3.0099 -3.5052)
			(stroke
				(width 0.1524)
				(type default)
			)
			(layer "F.SilkS")
		)
		(fp_line
			(start 2.9718 3.429)
			(end -3.0099 3.429)
			(stroke
				(width 0.1524)
				(type default)
			)
			(layer "F.SilkS")
		)
		(fp_line
			(start -3.0099 -3.5052)
			(end 2.9718 -3.5052)
			(stroke
				(width 0.1524)
				(type default)
			)
			(layer "F.SilkS")
		)
		(fp_line
			(start 2.9718 -3.5052)
			(end 2.9718 3.429)
			(stroke
				(width 0.1524)
				(type default)
			)
			(layer "F.SilkS")
		)
		(fp_circle
			(center -3.057398 -2.678684)
			(end -3.057398 -2.805684)
			(stroke
				(width 0.254)
				(type default)
			)
			(fill no)
			(layer "F.SilkS")
		)
		(fp_poly
			(pts
				(xy -2.9972 -3.4925) (xy -2.9972 -2.6924) (xy -2.1971 -3.4925)
			)
			(stroke
				(width 0)
				(type default)
			)
			(fill yes)
			(layer "F.SilkS")
		)
		(fp_poly
			(pts
				(xy -2.549906 -3.050032) (xy -2.549906 3.050032) (xy 2.549906 3.050032) (xy 2.549906 -3.050032)
			)
			(stroke
				(width 0)
				(type default)
			)
			(fill no)
			(layer "F.CrtYd")
		)
		(fp_line
			(start -2.549906 3.050032)
			(end -2.549906 -3.050032)
			(stroke
				(width 0.1)
				(type default)
			)
			(layer "F.Fab")
		)
		(fp_line
			(start 2.549906 3.050032)
			(end -2.549906 3.050032)
			(stroke
				(width 0.1)
				(type default)
			)
			(layer "F.Fab")
		)
		(fp_line
			(start -2.549906 -3.050032)
			(end 2.549906 -3.050032)
			(stroke
				(width 0.1)
				(type default)
			)
			(layer "F.Fab")
		)
		(fp_line
			(start 2.549906 -3.050032)
			(end 2.549906 3.050032)
			(stroke
				(width 0.1)
				(type default)
			)
			(layer "F.Fab")
		)
		(fp_circle
			(center -3.057398 -2.678684)
			(end -3.057398 -2.805684)
			(stroke
				(width 0.254)
				(type default)
			)
			(fill no)
			(layer "F.Fab")
		)
		(pad "1" smd rect
			(at -2.39522 -2.279904 270)
			(size 0.7112 0.254)
			(layers "F.Cu" "F.Mask" "F.Paste")
			(net "PVCCIO_CPU0")
		)
		(pad "2" smd rect
			(at -2.39522 -1.83007 270)
			(size 0.7112 0.254)
			(layers "F.Cu" "F.Mask" "F.Paste")
			(net "GND")
		)
		(pad "3" smd rect
			(at -2.39522 -1.379982 270)
			(size 0.7112 0.254)
			(layers "F.Cu" "F.Mask" "F.Paste")
			(net "VR_PVCCIO_CPU0_PH1_VCIN")
		)
		(pad "4" smd rect
			(at -2.39522 -0.929894 270)
			(size 0.7112 0.254)
			(layers "F.Cu" "F.Mask" "F.Paste")
			(net "P5V_STBY")
		)
		(pad "5" smd rect
			(at -2.39522 -0.48006 270)
			(size 0.7112 0.254)
			(layers "F.Cu" "F.Mask" "F.Paste")
			(net "GND")
		)
		(pad "6" smd rect
			(at -2.39522 -0.029972 270)
			(size 0.7112 0.254)
			(layers "F.Cu" "F.Mask" "F.Paste")
			(net "TP_PVCCIO_CPU0_GL_0")
		)
		(pad "7" smd custom
			(at 0.016764 1.145032 270)
			(size 0.53975 0.53975)
			(layers "F.Cu" "F.Mask" "F.Paste")
			(net "GND")
			(options
				(clearance outline)
				(anchor circle)
			)
			(primitives
				(gr_poly
					(pts
						(xy -2.7051 1.0795) (xy -2.7051 -0.3683) (xy -0.9271 -0.3683) (xy -0.9271 -1.0795) (xy 2.7051 -1.0795)
						(xy 2.7051 1.0795)
					)
					(width 0)
					(fill yes)
				)
			)
		)
		(pad "10" smd rect
			(at -0.008382 2.874772 270)
			(size 4.3434 0.6096)
			(layers "F.Cu" "F.Mask" "F.Paste")
			(net "VR_PVCCIO_CPU0_PH1_SW")
		)
		(pad "25" smd rect
			(at 1.548384 -1.283208 270)
			(size 2.3368 2.0066)
			(layers "F.Cu" "F.Mask" "F.Paste")
			(net "VR_FET_SW_P12V_STBY_PVCCIO_CPU0")
		)
		(pad "30" smd rect
			(at 2.050034 -2.895092 270)
			(size 0.254 0.7112)
			(layers "F.Cu" "F.Mask" "F.Paste")
			(net "VR_FET_SW_P12V_STBY_PVCCIO_CPU0")
		)
		(pad "31" smd rect
			(at 1.599946 -2.895092 270)
			(size 0.254 0.7112)
			(layers "F.Cu" "F.Mask" "F.Paste")
			(net "Net_366")
		)
		(pad "32" smd rect
			(at 1.150112 -2.895092 270)
			(size 0.254 0.7112)
			(layers "F.Cu" "F.Mask" "F.Paste")
			(net "VR_PVCCIO_CPU0_PH1_PHASE")
		)
		(pad "33" smd rect
			(at 0.700024 -2.895092 270)
			(size 0.254 0.7112)
			(layers "F.Cu" "F.Mask" "F.Paste")
			(net "VR_PVCCIO_CPU0_PH1_BOOT_R")
		)
		(pad "34" smd rect
			(at 0.249936 -2.895092 270)
			(size 0.254 0.7112)
			(layers "F.Cu" "F.Mask" "F.Paste")
			(net "VR_PVCCIO_CPU0_PWM1")
		)
		(pad "35" smd rect
			(at -0.199898 -2.895092 270)
			(size 0.254 0.7112)
			(layers "F.Cu" "F.Mask" "F.Paste")
			(net "P5V_STBY")
		)
		(pad "36" smd rect
			(at -0.649986 -2.895092 270)
			(size 0.254 0.7112)
			(layers "F.Cu" "F.Mask" "F.Paste")
			(net "A_TSENSE_PVCCIO_CPU0")
		)
		(pad "37" smd rect
			(at -1.100074 -2.895092 270)
			(size 0.254 0.7112)
			(layers "F.Cu" "F.Mask" "F.Paste")
			(net "VR_PVCCIO_CPU0_OCSET")
		)
		(pad "38" smd rect
			(at -1.549908 -2.895092 270)
			(size 0.254 0.7112)
			(layers "F.Cu" "F.Mask" "F.Paste")
			(net "ISENSE_PVCCIO_CPU0_PH1_IMON")
		)
		(pad "39" smd rect
			(at -1.999996 -2.895092 270)
			(size 0.254 0.7112)
			(layers "F.Cu" "F.Mask" "F.Paste")
			(net "VR_PVCCIO_CPU0_AIREF1")
		)
		(pad "40" smd rect
			(at -0.871728 -1.283208 270)
			(size 1.8034 2.0066)
			(layers "F.Cu" "F.Mask" "F.Paste")
			(net "GND")
		)
		(pad "41" smd rect
			(at -1.533906 0.247904 270)
			(size 0.508 0.3556)
			(layers "F.Cu" "F.Mask" "F.Paste")
			(net "TP_PVCCIO_CPU0_GL_1")
		)
	)
	(footprint ""
		(layer "F.Cu")
		(at 372.6053 -137.0457)
		(property "Reference" "C7A32"
			(at 0 0 0)
			(layer "F.SilkS")
			(hide yes)
			(effects
				(font
					(size 1.27 1.27)
				)
			)
		)
		(property "Value" ""
			(at 0 0 0)
			(layer "F.Fab")
			(effects
				(font
					(size 1.27 1.27)
				)
			)
		)
		(duplicate_pad_numbers_are_jumpers no)
		(fp_rect
			(start -0.7239 1.9939)
			(end 0.7239 -0.2159)
			(stroke
				(width 0)
				(type default)
			)
			(fill no)
			(layer "F.CrtYd")
		)
		(fp_line
			(start -0.7239 -0.2159)
			(end -0.7239 1.9939)
			(stroke
				(width 0.1)
				(type default)
			)
			(layer "F.Fab")
		)
		(fp_line
			(start -0.7239 1.9939)
			(end 0.7239 1.9939)
			(stroke
				(width 0.1)
				(type default)
			)
			(layer "F.Fab")
		)
		(fp_line
			(start 0.7239 -0.2159)
			(end -0.7239 -0.2159)
			(stroke
				(width 0.1)
				(type default)
			)
			(layer "F.Fab")
		)
		(fp_line
			(start 0.7239 1.9939)
			(end 0.7239 -0.2159)
			(stroke
				(width 0.1)
				(type default)
			)
			(layer "F.Fab")
		)
		(pad "1" smd rect
			(at 0 0)
			(size 1.27 1.016)
			(layers "F.Cu" "F.Mask" "F.Paste")
			(net "PVNN_PCH_STBY")
		)
		(pad "2" smd rect
			(at 0 1.778)
			(size 1.27 1.016)
			(layers "F.Cu" "F.Mask" "F.Paste")
			(net "GND")
		)
		(zone
			(layer "F.Cu")
			(hatch none 0.5)
			(connect_pads
				(clearance 0)
			)
			(min_thickness 0.25)
			(keepout
				(tracks not_allowed)
				(vias allowed)
				(pads allowed)
				(copperpour not_allowed)
				(footprints allowed)
			)
			(placement
				(enabled no)
				(sheetname "")
			)
			(fill
				(thermal_gap 0.5)
				(thermal_bridge_width 0.5)
				(island_removal_mode 0)
			)
			(polygon
				(pts
					(xy 371.9703 -135.7757) (xy 373.2403 -135.7757) (xy 373.2403 -136.5377) (xy 371.9703 -136.5377)
				)
			)
		)
	)
	(footprint ""
		(layer "F.Cu")
		(at 186.309 -64.77 90)
		(property "Reference" "C4D45"
			(at 0 0 90)
			(layer "F.SilkS")
			(hide yes)
			(effects
				(font
					(size 1.27 1.27)
				)
			)
		)
		(property "Value" ""
			(at 0 0 90)
			(layer "F.Fab")
			(effects
				(font
					(size 1.27 1.27)
				)
			)
		)
		(duplicate_pad_numbers_are_jumpers no)
		(fp_rect
			(start -0.3048 -0.1016)
			(end 0.3048 0.9906)
			(stroke
				(width 0)
				(type default)
			)
			(fill no)
			(layer "F.CrtYd")
		)
		(fp_line
			(start 0.3048 -0.1016)
			(end -0.3048 -0.1016)
			(stroke
				(width 0.1)
				(type default)
			)
			(layer "F.Fab")
		)
		(fp_line
			(start -0.3048 -0.1016)
			(end -0.3048 0.9906)
			(stroke
				(width 0.1)
				(type default)
			)
			(layer "F.Fab")
		)
		(fp_line
			(start 0.3048 0.9906)
			(end 0.3048 -0.1016)
			(stroke
				(width 0.1)
				(type default)
			)
			(layer "F.Fab")
		)
		(fp_line
			(start -0.3048 0.9906)
			(end 0.3048 0.9906)
			(stroke
				(width 0.1)
				(type default)
			)
			(layer "F.Fab")
		)
		(pad "1" smd rect
			(at 0 0 90)
			(size 0.508 0.508)
			(layers "F.Cu" "F.Mask" "F.Paste")
			(net "VSENSE_PVCCIN_CPU0_AVSP")
		)
		(pad "2" smd rect
			(at 0 0.889 90)
			(size 0.508 0.508)
			(layers "F.Cu" "F.Mask" "F.Paste")
			(net "VSENSE_PVCCIN_CPU0_N")
		)
		(zone
			(layer "F.Cu")
			(hatch none 0.5)
			(connect_pads
				(clearance 0)
			)
			(min_thickness 0.25)
			(keepout
				(tracks not_allowed)
				(vias allowed)
				(pads allowed)
				(copperpour not_allowed)
				(footprints allowed)
			)
			(placement
				(enabled no)
				(sheetname "")
			)
			(fill
				(thermal_gap 0.5)
				(thermal_bridge_width 0.5)
				(island_removal_mode 0)
			)
			(polygon
				(pts
					(xy 186.563 -64.516) (xy 186.944 -64.516) (xy 186.944 -65.024) (xy 186.563 -65.024)
				)
			)
		)
		(zone
			(layer "F.Cu")
			(hatch none 0.5)
			(connect_pads
				(clearance 0)
			)
			(min_thickness 0.25)
			(keepout
				(tracks allowed)
				(vias not_allowed)
				(pads allowed)
				(copperpour not_allowed)
				(footprints allowed)
			)
			(placement
				(enabled no)
				(sheetname "")
			)
			(fill
				(thermal_gap 0.5)
				(thermal_bridge_width 0.5)
				(island_removal_mode 0)
			)
			(polygon
				(pts
					(xy 186.563 -64.516) (xy 186.944 -64.516) (xy 186.944 -65.024) (xy 186.563 -65.024)
				)
			)
		)
	)
)
